(kicad_pcb
	(version 20211014)
	(generator pcbnew)
	(general
    (thickness 1.6)
  )
	(paper "A4")
	(title_block
    (title "SA800U (Snapdragon 845) Baseboard")
    (date "2023-10-19")
    (rev "1.0.3")
    (company "Antmicro Ltd.")
    (comment 1 "www.antmicro.com")
		(comment 9 "footprints 422-427 of 589")
	)
	(layers
    (0 "F.Cu" signal)
    (1 "In1.Cu" power)
    (2 "In2.Cu" signal)
    (3 "In3.Cu" signal)
    (4 "In4.Cu" power)
    (31 "B.Cu" signal)
    (32 "B.Adhes" user "B.Adhesive")
    (33 "F.Adhes" user "F.Adhesive")
    (34 "B.Paste" user)
    (35 "F.Paste" user)
    (36 "B.SilkS" user "B.Silkscreen")
    (37 "F.SilkS" user "F.Silkscreen")
    (38 "B.Mask" user)
    (39 "F.Mask" user)
    (40 "Dwgs.User" user "User.Drawings")
    (41 "Cmts.User" user "User.Comments")
    (42 "Eco1.User" user "User.Eco1")
    (43 "Eco2.User" user "User.Eco2")
    (44 "Edge.Cuts" user)
    (45 "Margin" user)
    (46 "B.CrtYd" user "B.Courtyard")
    (47 "F.CrtYd" user "F.Courtyard")
    (48 "B.Fab" user)
    (49 "F.Fab" user)
  )
	(footprint "sa800u-baseboard-hw-footprints:Nexperia_DFN-10_2.5x1mm_P0.5mm" (layer "B.Cu")
    (tedit 6215DC23)
    (at 133.519 100.7925)
    (property "Author" "Antmicro")
    (property "License" "Apache-2.0")
    (property "MPN" "PUSB3F96X")
    (property "Manufacturer" "Nexperia")
    (property "Sheetfile" "other-interfaces.kicad_sch")
    (property "Sheetname" "Other Interfaces")
    (attr smd)
    (fp_text reference "D22" (at 0.96 1.59 180) (layer "B.SilkS")
      (effects (font (size 0.7 0.7) (thickness 0.15)) (justify left bottom mirror))
    )
    (fp_text value "PUSB3F96X_PASS" (at -0.016 -1.705 180) (layer "B.Fab")
      (effects (font (size 0.7 0.7) (thickness 0.15)) (justify left bottom mirror))
    )
    (fp_text user "Author: Antmicro" (at -1.367 -4.905 180) (layer "B.Fab") hide
      (effects (font (size 0.7 0.7) (thickness 0.15)) (justify left bottom mirror))
    )
    (fp_text user "License: Apache-2.0" (at -1.367 -6.105 180) (layer "B.Fab") hide
      (effects (font (size 0.7 0.7) (thickness 0.15)) (justify left bottom mirror))
    )
    (fp_text user "${REFERENCE}" (at -1.367 -3.704 180) (layer "B.Fab") hide
      (effects (font (size 0.7 0.7) (thickness 0.15)) (justify left bottom mirror))
    )
    (fp_line (start 1.233 -0.405) (end 1.233 0.396) (layer "B.SilkS") (width 0.15))
    (fp_line (start -1.266 0.396) (end -1.266 -0.405) (layer "B.SilkS") (width 0.15))
    (fp_circle (center -1.317 -0.704) (end -1.266 -0.704) (layer "B.SilkS") (width 0.15) (fill solid))
    (fp_rect (start -1.4 0.7) (end 1.4 -0.7) (layer "B.CrtYd") (width 0.05) (fill none))
    (pad "1" smd rect (at -1.016 -0.392) (size 0.2 0.475) (layers "B.Cu" "B.Paste" "B.Mask")
      (net 248 "/Other Interfaces/SD_CMD_R") (pinfunction "CH1") (pintype "passive"))
    (pad "2" smd rect (at -0.517 -0.392) (size 0.2 0.475) (layers "B.Cu" "B.Paste" "B.Mask")
      (net 249 "/Other Interfaces/SD_DATA3_R") (pinfunction "CH2") (pintype "passive"))
    (pad "3" smd rect (at -0.016 -0.392) (size 0.2 0.475) (layers "B.Cu" "B.Paste" "B.Mask")
      (net 1 "GND") (pinfunction "GND") (pintype "passive"))
    (pad "4" smd rect (at 0.482 -0.392) (size 0.2 0.475) (layers "B.Cu" "B.Paste" "B.Mask")
      (net 247 "/Other Interfaces/SD_DATA2_R") (pinfunction "CH3") (pintype "passive"))
    (pad "5" smd rect (at 0.982 -0.392) (size 0.2 0.475) (layers "B.Cu" "B.Paste" "B.Mask")
      (net 246 "/Other Interfaces/SD_DET_R") (pinfunction "CH4") (pintype "passive"))
    (pad "6" smd rect (at 0.982 0.383 180) (size 0.2 0.475) (layers "B.Cu" "B.Paste" "B.Mask")
      (net 246 "/Other Interfaces/SD_DET_R") (pinfunction "CH4") (pintype "passive"))
    (pad "7" smd rect (at 0.482 0.383 180) (size 0.2 0.475) (layers "B.Cu" "B.Paste" "B.Mask")
      (net 247 "/Other Interfaces/SD_DATA2_R") (pinfunction "CH3") (pintype "passive"))
    (pad "8" smd rect (at -0.016 0.383 180) (size 0.2 0.475) (layers "B.Cu" "B.Paste" "B.Mask")
      (net 1 "GND") (pinfunction "GND") (pintype "passive"))
    (pad "9" smd rect (at -0.517 0.383 180) (size 0.2 0.475) (layers "B.Cu" "B.Paste" "B.Mask")
      (net 249 "/Other Interfaces/SD_DATA3_R") (pinfunction "CH2") (pintype "passive"))
    (pad "10" smd rect (at -1.016 0.383 180) (size 0.2 0.475) (layers "B.Cu" "B.Paste" "B.Mask")
      (net 248 "/Other Interfaces/SD_CMD_R") (pinfunction "CH1") (pintype "passive"))
  )
	(footprint "sa800u-baseboard-hw-footprints:Nexperia_DFN-10_2.5x1mm_P0.5mm" (layer "B.Cu")
    (tedit 6215DC23)
    (at 128.36 100.79)
    (property "Author" "Antmicro")
    (property "License" "Apache-2.0")
    (property "MPN" "PUSB3F96X")
    (property "Manufacturer" "Nexperia")
    (property "Sheetfile" "other-interfaces.kicad_sch")
    (property "Sheetname" "Other Interfaces")
    (attr smd)
    (fp_text reference "D23" (at 1.04 1.55 180) (layer "B.SilkS")
      (effects (font (size 0.7 0.7) (thickness 0.15)) (justify left bottom mirror))
    )
    (fp_text value "PUSB3F96X_PASS" (at -0.016 -1.705 180) (layer "B.Fab")
      (effects (font (size 0.7 0.7) (thickness 0.15)) (justify left bottom mirror))
    )
    (fp_text user "Author: Antmicro" (at -1.367 -4.905 180) (layer "B.Fab") hide
      (effects (font (size 0.7 0.7) (thickness 0.15)) (justify left bottom mirror))
    )
    (fp_text user "${REFERENCE}" (at -1.367 -3.704 180) (layer "B.Fab") hide
      (effects (font (size 0.7 0.7) (thickness 0.15)) (justify left bottom mirror))
    )
    (fp_text user "License: Apache-2.0" (at -1.367 -6.105 180) (layer "B.Fab") hide
      (effects (font (size 0.7 0.7) (thickness 0.15)) (justify left bottom mirror))
    )
    (fp_line (start 1.233 -0.405) (end 1.233 0.396) (layer "B.SilkS") (width 0.15))
    (fp_line (start -1.266 0.396) (end -1.266 -0.405) (layer "B.SilkS") (width 0.15))
    (fp_circle (center -1.317 -0.704) (end -1.266 -0.704) (layer "B.SilkS") (width 0.15) (fill solid))
    (fp_rect (start -1.4 0.7) (end 1.4 -0.7) (layer "B.CrtYd") (width 0.05) (fill none))
    (pad "1" smd rect (at -1.016 -0.392) (size 0.2 0.475) (layers "B.Cu" "B.Paste" "B.Mask")
      (net 251 "/Other Interfaces/SD_DATA1_R") (pinfunction "CH1") (pintype "passive"))
    (pad "2" smd rect (at -0.517 -0.392) (size 0.2 0.475) (layers "B.Cu" "B.Paste" "B.Mask")
      (net 252 "/Other Interfaces/SD_DATA0_R") (pinfunction "CH2") (pintype "passive"))
    (pad "3" smd rect (at -0.016 -0.392) (size 0.2 0.475) (layers "B.Cu" "B.Paste" "B.Mask")
      (net 1 "GND") (pinfunction "GND") (pintype "passive"))
    (pad "4" smd rect (at 0.482 -0.392) (size 0.2 0.475) (layers "B.Cu" "B.Paste" "B.Mask")
      (net 250 "/Other Interfaces/SD_CLK_R") (pinfunction "CH3") (pintype "passive"))
    (pad "5" smd rect (at 0.982 -0.392) (size 0.2 0.475) (layers "B.Cu" "B.Paste" "B.Mask")
      (net 227 "/Other Interfaces/SD_VDD_R") (pinfunction "CH4") (pintype "passive"))
    (pad "6" smd rect (at 0.982 0.383 180) (size 0.2 0.475) (layers "B.Cu" "B.Paste" "B.Mask")
      (net 227 "/Other Interfaces/SD_VDD_R") (pinfunction "CH4") (pintype "passive"))
    (pad "7" smd rect (at 0.482 0.383 180) (size 0.2 0.475) (layers "B.Cu" "B.Paste" "B.Mask")
      (net 250 "/Other Interfaces/SD_CLK_R") (pinfunction "CH3") (pintype "passive"))
    (pad "8" smd rect (at -0.016 0.383 180) (size 0.2 0.475) (layers "B.Cu" "B.Paste" "B.Mask")
      (net 1 "GND") (pinfunction "GND") (pintype "passive"))
    (pad "9" smd rect (at -0.517 0.383 180) (size 0.2 0.475) (layers "B.Cu" "B.Paste" "B.Mask")
      (net 252 "/Other Interfaces/SD_DATA0_R") (pinfunction "CH2") (pintype "passive"))
    (pad "10" smd rect (at -1.016 0.383 180) (size 0.2 0.475) (layers "B.Cu" "B.Paste" "B.Mask")
      (net 251 "/Other Interfaces/SD_DATA1_R") (pinfunction "CH1") (pintype "passive"))
  )
	(footprint "sa800u-baseboard-hw-footprints:R_0402_1005Metric" (layer "B.Cu")
    (tedit 5FD9C158)
    (at 81.35 120.4 -90)
    (descr "Resistor SMD 0402")
    (tags "resistor SMD 0402")
    (property "Author" "Antmicro")
    (property "License" "Apache-2.0")
    (property "MPN" "CR0402-FX-2201GLF")
    (property "Manufacturer" "Bourns")
    (property "Sheetfile" "psu.kicad_sch")
    (property "Sheetname" "PSU")
    (property "Tolerance" "1%")
    (property "Val" "2k2")
    (attr smd)
    (fp_text reference "R124" (at 0.78 -0.52 90) (layer "B.SilkS")
      (effects (font (size 0.7 0.7) (thickness 0.15)) (justify left bottom mirror))
    )
    (fp_text value "R_2k2_0402" (at 0 -1.4 90) (layer "B.Fab")
      (effects (font (size 0.7 0.7) (thickness 0.15)) (justify left bottom mirror))
    )
    (fp_text user "${REFERENCE}" (at -0.95 -3.168 90) (layer "B.Fab") hide
      (effects (font (size 0.7 0.7) (thickness 0.15)) (justify left bottom mirror))
    )
    (fp_text user "License: Apache-2.0" (at -0.95 -5.169 90) (layer "B.Fab") hide
      (effects (font (size 0.7 0.7) (thickness 0.15)) (justify left bottom mirror))
    )
    (fp_text user "Author: Antmicro" (at -0.95 -4.169 90) (layer "B.Fab") hide
      (effects (font (size 0.7 0.7) (thickness 0.15)) (justify left bottom mirror))
    )
    (fp_rect (start -0.93 0.47) (end 0.93 -0.47) (layer "B.CrtYd") (width 0.05) (fill none))
    (fp_rect (start -0.5 0.25) (end 0.5 -0.25) (layer "B.Fab") (width 0.15) (fill none))
    (pad "1" smd roundrect (at -0.485 0 270) (size 0.59 0.64) (layers "B.Cu" "B.Paste" "B.Mask") (roundrect_rratio 0.25)
      (net 405 "Net-(R123-Pad2)") (pintype "passive"))
    (pad "2" smd roundrect (at 0.485 0 270) (size 0.59 0.64) (layers "B.Cu" "B.Paste" "B.Mask") (roundrect_rratio 0.25)
      (net 1 "GND") (pintype "passive"))
  )
	(footprint "sa800u-baseboard-hw-footprints:F52R-1A7H1-11020" (layer "B.Cu")
    (tedit 6215E19A)
    (at 152 126.5 -90)
    (property "Author" "Antmicro")
    (property "License" "Apache-2.0")
    (property "MPN" "F52R-1A7H1-11020")
    (property "Manufacturer" "Amphenol")
    (property "Sheetfile" "lcm.kicad_sch")
    (property "Sheetname" "LCM")
    (attr smd)
    (fp_text reference "J6" (at -13.2 3.8 90) (layer "B.SilkS")
      (effects (font (size 0.65 0.65) (thickness 0.15)) (justify mirror))
    )
    (fp_text value "F52R-1A7H1-11020" (at 0 -1.2 90) (layer "B.Fab")
      (effects (font (size 0.65 0.65) (thickness 0.15)) (justify mirror))
    )
    (fp_text user "${REFERENCE}" (at 0 0 90) (layer "B.Fab")
      (effects (font (size 0.65 0.65) (thickness 0.15)) (justify mirror))
    )
    (fp_text user "License: Apache-2.0" (at -14.148 -7.559 90) (layer "B.Fab") hide
      (effects (font (size 0.7 0.7) (thickness 0.15)) (justify left bottom mirror))
    )
    (fp_text user "Author: Antmicro" (at -14.148 -6.358 90) (layer "B.Fab") hide
      (effects (font (size 0.7 0.7) (thickness 0.15)) (justify left bottom mirror))
    )
    (fp_line (start -14.022 -3.031) (end 14.019 -3.031) (layer "B.SilkS") (width 0.15))
    (fp_line (start 14.019 -3.031) (end 14.019 2.734) (layer "B.SilkS") (width 0.15))
    (fp_line (start 14.019 2.734) (end 9.992 2.734) (layer "B.SilkS") (width 0.15))
    (fp_line (start -9.994 2.734) (end -14.022 2.734) (layer "B.SilkS") (width 0.15))
    (fp_line (start -14.022 2.734) (end -14.022 -3.031) (layer "B.SilkS") (width 0.15))
    (fp_circle (center -10.2 2.4) (end -10.15 2.4) (layer "B.SilkS") (width 0.15) (fill solid))
    (fp_rect (start -14.4 3.1) (end 14.4 -3.4) (layer "B.CrtYd") (width 0.05) (fill none))
    (fp_line (start 13.893 -2.905) (end 13.893 2.606) (layer "B.Fab") (width 0.15))
    (fp_line (start -13.894 -2.905) (end 13.893 -2.905) (layer "B.Fab") (width 0.15))
    (fp_line (start -13.894 2.606) (end -13.894 -2.905) (layer "B.Fab") (width 0.15))
    (fp_line (start 13.893 2.606) (end -13.894 2.606) (layer "B.Fab") (width 0.15))
    (pad "1" smd rect (at -9.5 2.351 270) (size 0.3048 1.0922) (layers "B.Cu" "B.Paste" "B.Mask")
      (net 1 "GND") (pinfunction "1") (pintype "unspecified"))
    (pad "2" smd rect (at -8.5 2.351 270) (size 0.3048 1.0922) (layers "B.Cu" "B.Paste" "B.Mask")
      (net 318 "/LCM/DSI_LN3_L_N") (pinfunction "2") (pintype "unspecified"))
    (pad "3" smd rect (at -7.5 2.351 270) (size 0.3048 1.0922) (layers "B.Cu" "B.Paste" "B.Mask")
      (net 317 "/LCM/DSI_LN3_L_P") (pinfunction "3") (pintype "unspecified"))
    (pad "4" smd rect (at -6.5 2.351 270) (size 0.3048 1.0922) (layers "B.Cu" "B.Paste" "B.Mask")
      (net 1 "GND") (pinfunction "4") (pintype "unspecified"))
    (pad "5" smd rect (at -5.5 2.351 270) (size 0.3048 1.0922) (layers "B.Cu" "B.Paste" "B.Mask")
      (net 316 "/LCM/DSI_LN2_L_N") (pinfunction "5") (pintype "unspecified"))
    (pad "6" smd rect (at -4.5 2.351 270) (size 0.3048 1.0922) (layers "B.Cu" "B.Paste" "B.Mask")
      (net 315 "/LCM/DSI_LN2_L_P") (pinfunction "6") (pintype "unspecified"))
    (pad "7" smd rect (at -3.5 2.351 270) (size 0.3048 1.0922) (layers "B.Cu" "B.Paste" "B.Mask")
      (net 1 "GND") (pinfunction "7") (pintype "unspecified"))
    (pad "8" smd rect (at -2.5 2.351 270) (size 0.3048 1.0922) (layers "B.Cu" "B.Paste" "B.Mask")
      (net 314 "/LCM/DSI_LN1_L_N") (pinfunction "8") (pintype "unspecified"))
    (pad "9" smd rect (at -1.5 2.351 270) (size 0.3048 1.0922) (layers "B.Cu" "B.Paste" "B.Mask")
      (net 313 "/LCM/DSI_LN1_L_P") (pinfunction "9") (pintype "unspecified"))
    (pad "10" smd rect (at -0.5 2.351 270) (size 0.3048 1.0922) (layers "B.Cu" "B.Paste" "B.Mask")
      (net 1 "GND") (pinfunction "10") (pintype "unspecified"))
    (pad "11" smd rect (at 0.498 2.351 270) (size 0.3048 1.0922) (layers "B.Cu" "B.Paste" "B.Mask")
      (net 312 "/LCM/DSI_LN0_L_N") (pinfunction "11") (pintype "unspecified"))
    (pad "12" smd rect (at 1.499 2.351 270) (size 0.3048 1.0922) (layers "B.Cu" "B.Paste" "B.Mask")
      (net 311 "/LCM/DSI_LN0_L_P") (pinfunction "12") (pintype "unspecified"))
    (pad "13" smd rect (at 2.499 2.351 270) (size 0.3048 1.0922) (layers "B.Cu" "B.Paste" "B.Mask")
      (net 1 "GND") (pinfunction "13") (pintype "unspecified"))
    (pad "14" smd rect (at 3.499 2.351 270) (size 0.3048 1.0922) (layers "B.Cu" "B.Paste" "B.Mask")
      (net 310 "/LCM/DSI_CLK_L_N") (pinfunction "14") (pintype "unspecified"))
    (pad "15" smd rect (at 4.498 2.351 270) (size 0.3048 1.0922) (layers "B.Cu" "B.Paste" "B.Mask")
      (net 309 "/LCM/DSI_CLK_L_P") (pinfunction "15") (pintype "unspecified"))
    (pad "16" smd rect (at 5.499 2.351 270) (size 0.3048 1.0922) (layers "B.Cu" "B.Paste" "B.Mask")
      (net 1 "GND") (pinfunction "16") (pintype "unspecified"))
    (pad "17" smd rect (at 6.499 2.351 270) (size 0.3048 1.0922) (layers "B.Cu" "B.Paste" "B.Mask")
      (net 148 "/LCM/TP_I2C_SCL_3V3") (pinfunction "17") (pintype "unspecified"))
    (pad "18" smd rect (at 7.499 2.351 270) (size 0.3048 1.0922) (layers "B.Cu" "B.Paste" "B.Mask")
      (net 149 "/LCM/TP_I2C_SDA_3V3") (pinfunction "18") (pintype "unspecified"))
    (pad "19" smd rect (at 8.499 2.351 270) (size 0.3048 1.0922) (layers "B.Cu" "B.Paste" "B.Mask")
      (net 1 "GND") (pinfunction "19") (pintype "unspecified"))
    (pad "20" smd rect (at 9.499 2.351 270) (size 0.3048 1.0922) (layers "B.Cu" "B.Paste" "B.Mask")
      (net 131 "3V3_SYS") (pinfunction "20") (pintype "unspecified"))
    (pad "21" smd rect (at -11.85 1.18 180) (size 2.0541 1.40005) (layers "B.Cu" "B.Paste" "B.Mask")
      (net 662 "unconnected-(J6-Pad21)") (pinfunction "SH1") (pintype "unspecified+no_connect"))
    (pad "21" smd rect (at -12.251 1.357 270) (size 2.1082 1.6002) (layers "B.Cu" "B.Paste" "B.Mask")
      (net 662 "unconnected-(J6-Pad21)") (pinfunction "SH1") (pintype "unspecified+no_connect"))
    (pad "22" smd rect (at 12.249 1.357 270) (size 2.1082 1.6002) (layers "B.Cu" "B.Paste" "B.Mask")
      (net 663 "unconnected-(J6-Pad22)") (pinfunction "SH2") (pintype "unspecified+no_connect"))
    (pad "22" smd rect (at 11.84 1.18 180) (size 2.0541 1.40005) (layers "B.Cu" "B.Paste" "B.Mask")
      (net 663 "unconnected-(J6-Pad22)") (pinfunction "SH2") (pintype "unspecified+no_connect"))
  )
	(footprint "sa800u-baseboard-hw-footprints:R_0402_1005Metric" (layer "B.Cu")
    (tedit 5FD9C158)
    (at 75.6 121.25)
    (descr "Resistor SMD 0402")
    (tags "resistor SMD 0402")
    (property "Author" "Antmicro")
    (property "License" "Apache-2.0")
    (property "MPN" "CR0402-FX-2201GLF")
    (property "Manufacturer" "Bourns")
    (property "Sheetfile" "psu.kicad_sch")
    (property "Sheetname" "PSU")
    (property "Tolerance" "1%")
    (property "Val" "2k2")
    (attr smd)
    (fp_text reference "R125" (at -0.22 -4.79 180) (layer "B.SilkS")
      (effects (font (size 0.7 0.7) (thickness 0.15)) (justify left bottom mirror))
    )
    (fp_text value "R_2k2_0402" (at 0 -1.4 180) (layer "B.Fab")
      (effects (font (size 0.7 0.7) (thickness 0.15)) (justify left bottom mirror))
    )
    (fp_text user "License: Apache-2.0" (at -0.95 -5.169 180) (layer "B.Fab") hide
      (effects (font (size 0.7 0.7) (thickness 0.15)) (justify left bottom mirror))
    )
    (fp_text user "Author: Antmicro" (at -0.95 -4.169 180) (layer "B.Fab") hide
      (effects (font (size 0.7 0.7) (thickness 0.15)) (justify left bottom mirror))
    )
    (fp_text user "${REFERENCE}" (at -0.95 -3.168 180) (layer "B.Fab") hide
      (effects (font (size 0.7 0.7) (thickness 0.15)) (justify left bottom mirror))
    )
    (fp_rect (start -0.93 0.47) (end 0.93 -0.47) (layer "B.CrtYd") (width 0.05) (fill none))
    (fp_rect (start -0.5 0.25) (end 0.5 -0.25) (layer "B.Fab") (width 0.15) (fill none))
    (pad "1" smd roundrect (at -0.485 0) (size 0.59 0.64) (layers "B.Cu" "B.Paste" "B.Mask") (roundrect_rratio 0.25)
      (net 74 "VDD") (pintype "passive"))
    (pad "2" smd roundrect (at 0.485 0) (size 0.59 0.64) (layers "B.Cu" "B.Paste" "B.Mask") (roundrect_rratio 0.25)
      (net 406 "Net-(R125-Pad2)") (pintype "passive"))
  )
	(footprint "sa800u-baseboard-hw-footprints:R_0402_1005Metric" (layer "B.Cu")
    (tedit 5FD9C158)
    (at 73.6 121.25 180)
    (descr "Resistor SMD 0402")
    (tags "resistor SMD 0402")
    (property "Author" "Antmicro")
    (property "License" "Apache-2.0")
    (property "MPN" "CR0402-FX-1001GLF")
    (property "Manufacturer" "Bourns")
    (property "Sheetfile" "psu.kicad_sch")
    (property "Sheetname" "PSU")
    (property "Tolerance" "1%")
    (property "Val" "1k")
    (attr smd)
    (fp_text reference "R126" (at 0.82 4.75) (layer "B.SilkS")
      (effects (font (size 0.7 0.7) (thickness 0.15)) (justify left bottom mirror))
    )
    (fp_text value "R_1k_0402" (at 0 -1.4) (layer "B.Fab")
      (effects (font (size 0.7 0.7) (thickness 0.15)) (justify left bottom mirror))
    )
    (fp_text user "${REFERENCE}" (at -0.95 -3.168) (layer "B.Fab") hide
      (effects (font (size 0.7 0.7) (thickness 0.15)) (justify left bottom mirror))
    )
    (fp_text user "Author: Antmicro" (at -0.95 -4.169) (layer "B.Fab") hide
      (effects (font (size 0.7 0.7) (thickness 0.15)) (justify left bottom mirror))
    )
    (fp_text user "License: Apache-2.0" (at -0.95 -5.169) (layer "B.Fab") hide
      (effects (font (size 0.7 0.7) (thickness 0.15)) (justify left bottom mirror))
    )
    (fp_rect (start -0.93 0.47) (end 0.93 -0.47) (layer "B.CrtYd") (width 0.05) (fill none))
    (fp_rect (start -0.5 0.25) (end 0.5 -0.25) (layer "B.Fab") (width 0.15) (fill none))
    (pad "1" smd roundrect (at -0.485 0 180) (size 0.59 0.64) (layers "B.Cu" "B.Paste" "B.Mask") (roundrect_rratio 0.25)
      (net 406 "Net-(R125-Pad2)") (pintype "passive"))
    (pad "2" smd roundrect (at 0.485 0 180) (size 0.59 0.64) (layers "B.Cu" "B.Paste" "B.Mask") (roundrect_rratio 0.25)
      (net 390 "Net-(Q15-Pad1)") (pintype "passive"))
  )
)
